(kicad_pcb
	(version 20241229)
	(generator "pcbnew")
	(generator_version "9.0")
	(general
		(thickness 1.6642)
		(legacy_teardrops no)
	)
	(paper "A3")
	(title_block
		(title "PolarFire SoM")
		(date "2025-07-22")
		(rev "1.1.4")
		(company "Antmicro Ltd")
		(comment 1 "www.antmicro.com")
		(comment 9 "footprints 170-173 of 470")
	)
	(layers
		(0 "F.Cu" mixed)
		(4 "In1.Cu" power)
		(6 "In2.Cu" signal)
		(8 "In3.Cu" power)
		(10 "In4.Cu" signal)
		(12 "In5.Cu" power)
		(14 "In6.Cu" power)
		(16 "In7.Cu" signal)
		(18 "In8.Cu" power)
		(20 "In9.Cu" signal)
		(22 "In10.Cu" power)
		(24 "In11.Cu" signal)
		(26 "In12.Cu" signal)
		(2 "B.Cu" mixed)
		(9 "F.Adhes" user "F.Adhesive")
		(11 "B.Adhes" user "B.Adhesive")
		(13 "F.Paste" user)
		(15 "B.Paste" user)
		(5 "F.SilkS" user "F.Silkscreen")
		(7 "B.SilkS" user "B.Silkscreen")
		(1 "F.Mask" user)
		(3 "B.Mask" user)
		(17 "Dwgs.User" user "User.Drawings")
		(19 "Cmts.User" user "User.Comments")
		(21 "Eco1.User" user "User.Eco1")
		(23 "Eco2.User" user "User.Eco2")
		(25 "Edge.Cuts" user)
		(27 "Margin" user)
		(31 "F.CrtYd" user "F.Courtyard")
		(29 "B.CrtYd" user "B.Courtyard")
		(35 "F.Fab" user)
		(33 "B.Fab" user)
	)
	(footprint "antmicro-footprints:C_0402_1005Metric"
		(layer "B.Cu")
		(at 214.982486 143.297401 90)
		(descr "Capacitor SMD 0402")
		(tags "capacitor SMD 0402")
		(property "Reference" "C184"
			(at 2.857401 0.117514 90)
			(layer "B.SilkS")
			(effects
				(font
					(size 0.7 0.7)
					(thickness 0.15)
				)
				(justify right bottom mirror)
			)
		)
		(property "Value" "C_100n_0402"
			(at -1.022927 -2.155213 90)
			(layer "B.Fab")
			(hide yes)
			(effects
				(font
					(size 0.7 0.7)
					(thickness 0.15)
				)
				(justify right bottom mirror)
			)
		)
		(property "Datasheet" "https://www.murata.com/products/productdetail?partno=GRM155R61H104KE14%23"
			(at 0 0 90)
			(layer "F.Fab")
			(hide yes)
			(effects
				(font
					(size 1.27 1.27)
					(thickness 0.15)
				)
			)
		)
		(property "Description" "SMD Multilayer Ceramic Capacitor, 0.1 µF, 50 V, 0402 [1005 Metric], ± 10%, X5R, GRM Series"
			(at 0 0 90)
			(layer "F.Fab")
			(hide yes)
			(effects
				(font
					(size 1.27 1.27)
					(thickness 0.15)
				)
			)
		)
		(property "Author" "Antmicro"
			(at 358.279887 -71.685085 0)
			(layer "B.Fab")
			(hide yes)
			(effects
				(font
					(size 1 1)
					(thickness 0.15)
				)
				(justify mirror)
			)
		)
		(property "Dielectric" "X5R"
			(at 358.279887 -71.685085 0)
			(layer "B.Fab")
			(hide yes)
			(effects
				(font
					(size 1 1)
					(thickness 0.15)
				)
				(justify mirror)
			)
		)
		(property "License" "Apache-2.0"
			(at 358.279887 -71.685085 0)
			(layer "B.Fab")
			(hide yes)
			(effects
				(font
					(size 1 1)
					(thickness 0.15)
				)
				(justify mirror)
			)
		)
		(property "MPN" "GRM155R61H104KE14D"
			(at 358.279887 -71.685085 0)
			(layer "B.Fab")
			(hide yes)
			(effects
				(font
					(size 1 1)
					(thickness 0.15)
				)
				(justify mirror)
			)
		)
		(property "Manufacturer" "Murata"
			(at 358.279887 -71.685085 0)
			(layer "B.Fab")
			(hide yes)
			(effects
				(font
					(size 1 1)
					(thickness 0.15)
				)
				(justify mirror)
			)
		)
		(property "Public" ""
			(at 358.279887 -71.685085 0)
			(layer "B.Fab")
			(hide yes)
			(effects
				(font
					(size 1 1)
					(thickness 0.15)
				)
				(justify mirror)
			)
		)
		(property "Val" "100n"
			(at 358.279887 -71.685085 0)
			(layer "B.Fab")
			(hide yes)
			(effects
				(font
					(size 1 1)
					(thickness 0.15)
				)
				(justify mirror)
			)
		)
		(property "Voltage" "50V"
			(at 358.279887 -71.685085 0)
			(layer "B.Fab")
			(hide yes)
			(effects
				(font
					(size 1 1)
					(thickness 0.15)
				)
				(justify mirror)
			)
		)
		(sheetname "/USB/")
		(sheetfile "usb.kicad_sch")
		(attr smd)
		(fp_rect
			(start -0.925 0.47)
			(end 0.925 -0.47)
			(stroke
				(width 0.05)
				(type default)
			)
			(fill no)
			(layer "B.CrtYd")
		)
		(fp_line
			(start 0.504 -0.248)
			(end -0.494 -0.248)
			(stroke
				(width 0.15)
				(type solid)
			)
			(layer "B.Fab")
		)
		(fp_line
			(start -0.494 -0.248)
			(end -0.494 0.25)
			(stroke
				(width 0.15)
				(type solid)
			)
			(layer "B.Fab")
		)
		(fp_line
			(start 0.504 0.25)
			(end 0.504 -0.248)
			(stroke
				(width 0.15)
				(type solid)
			)
			(layer "B.Fab")
		)
		(fp_line
			(start -0.494 0.25)
			(end 0.504 0.25)
			(stroke
				(width 0.15)
				(type solid)
			)
			(layer "B.Fab")
		)
		(fp_text user "Author: Antmicro"
			(at -0.939 -3.399 270)
			(layer "B.Fab")
			(effects
				(font
					(size 0.7 0.7)
					(thickness 0.15)
				)
				(justify left bottom mirror)
			)
		)
		(fp_text user "${REFERENCE}"
			(at -0.939 -4.599 270)
			(layer "B.Fab")
			(effects
				(font
					(size 0.7 0.7)
					(thickness 0.15)
				)
				(justify left bottom mirror)
			)
		)
		(fp_text user "License: Apache-2.0"
			(at -0.939 -5.799 270)
			(layer "B.Fab")
			(effects
				(font
					(size 0.7 0.7)
					(thickness 0.15)
				)
				(justify left bottom mirror)
			)
		)
		(pad "1" smd roundrect
			(at -0.48 0 90)
			(size 0.59 0.64)
			(layers "B.Cu" "B.Mask" "B.Paste")
			(roundrect_rratio 0.25)
			(net 417 "GND")
			(pintype "passive")
		)
		(pad "2" smd roundrect
			(at 0.48 0 90)
			(size 0.59 0.64)
			(layers "B.Cu" "B.Mask" "B.Paste")
			(roundrect_rratio 0.25)
			(net 152 "/USB/VDDIO")
			(pintype "passive")
		)
	)
	(footprint "antmicro-footprints:R_0402_1005Metric"
		(layer "B.Cu")
		(at 224.38 131.6)
		(descr "Resistor SMD 0402")
		(tags "resistor SMD 0402")
		(property "Reference" "R81"
			(at 1.07 1.3 180)
			(layer "B.SilkS")
			(effects
				(font
					(size 0.7 0.7)
					(thickness 0.15)
				)
				(justify left bottom mirror)
			)
		)
		(property "Value" "R_100k_0402"
			(at -1.011843 -1.772047 180)
			(layer "B.Fab")
			(hide yes)
			(effects
				(font
					(size 0.7 0.7)
					(thickness 0.15)
				)
				(justify left bottom mirror)
			)
		)
		(property "Datasheet" "https://www.bourns.com/docs/product-datasheets/cr.pdf"
			(at 0 0 0)
			(layer "F.Fab")
			(hide yes)
			(effects
				(font
					(size 1.27 1.27)
					(thickness 0.15)
				)
			)
		)
		(property "Description" "SMD Chip Resistor, 100 kohm, ± 1%, 62.5 mW, 0402 [1005 Metric], Thick Film, General Purpose"
			(at 0 0 0)
			(layer "F.Fab")
			(hide yes)
			(effects
				(font
					(size 1.27 1.27)
					(thickness 0.15)
				)
			)
		)
		(property "Author" "Antmicro"
			(at 0 0 0)
			(layer "B.Fab")
			(hide yes)
			(effects
				(font
					(size 1 1)
					(thickness 0.15)
				)
				(justify mirror)
			)
		)
		(property "License" "Apache-2.0"
			(at 0 0 0)
			(layer "B.Fab")
			(hide yes)
			(effects
				(font
					(size 1 1)
					(thickness 0.15)
				)
				(justify mirror)
			)
		)
		(property "MPN" "CR0402-FX-1003GLF"
			(at 0 0 0)
			(layer "B.Fab")
			(hide yes)
			(effects
				(font
					(size 1 1)
					(thickness 0.15)
				)
				(justify mirror)
			)
		)
		(property "Manufacturer" "Bourns"
			(at 0 0 0)
			(layer "B.Fab")
			(hide yes)
			(effects
				(font
					(size 1 1)
					(thickness 0.15)
				)
				(justify mirror)
			)
		)
		(property "Public" ""
			(at 0 0 0)
			(layer "B.Fab")
			(hide yes)
			(effects
				(font
					(size 1 1)
					(thickness 0.15)
				)
				(justify mirror)
			)
		)
		(property "Tolerance" "1%"
			(at 0 0 0)
			(layer "B.Fab")
			(hide yes)
			(effects
				(font
					(size 1 1)
					(thickness 0.15)
				)
				(justify mirror)
			)
		)
		(property "Val" "100k"
			(at 0 0 0)
			(layer "B.Fab")
			(hide yes)
			(effects
				(font
					(size 1 1)
					(thickness 0.15)
				)
				(justify mirror)
			)
		)
		(sheetname "/FPGA GPIO/")
		(sheetfile "fpga-gpio.kicad_sch")
		(attr smd)
		(fp_rect
			(start -0.925 0.47)
			(end 0.925 -0.47)
			(stroke
				(width 0.05)
				(type default)
			)
			(fill no)
			(layer "B.CrtYd")
		)
		(fp_rect
			(start -0.5 0.25)
			(end 0.5 -0.25)
			(stroke
				(width 0.15)
				(type solid)
			)
			(fill no)
			(layer "B.Fab")
		)
		(fp_text user "Author: Antmicro"
			(at -0.95 -4.169 180)
			(layer "B.Fab")
			(effects
				(font
					(size 0.7 0.7)
					(thickness 0.15)
				)
				(justify left bottom mirror)
			)
		)
		(fp_text user "${REFERENCE}"
			(at -0.95 -3.168 180)
			(layer "B.Fab")
			(effects
				(font
					(size 0.7 0.7)
					(thickness 0.15)
				)
				(justify left bottom mirror)
			)
		)
		(fp_text user "License: Apache-2.0"
			(at -0.95 -5.169 180)
			(layer "B.Fab")
			(effects
				(font
					(size 0.7 0.7)
					(thickness 0.15)
				)
				(justify left bottom mirror)
			)
		)
		(pad "1" smd roundrect
			(at -0.48 0)
			(size 0.59 0.64)
			(layers "B.Cu" "B.Mask" "B.Paste")
			(roundrect_rratio 0.25)
			(net 417 "GND")
			(pintype "passive")
		)
		(pad "2" smd roundrect
			(at 0.48 0)
			(size 0.59 0.64)
			(layers "B.Cu" "B.Mask" "B.Paste")
			(roundrect_rratio 0.25)
			(net 341 "/FPGA GPIO/USER_LED_G")
			(pintype "passive")
		)
	)
	(footprint "antmicro-footprints:TP_SMD_0.75mm"
		(layer "B.Cu")
		(at 216.35 121.75 180)
		(property "Reference" "TP23"
			(at -3.04 -0.26 0)
			(layer "B.SilkS")
			(hide yes)
			(effects
				(font
					(size 0.7 0.7)
					(thickness 0.15)
				)
				(justify left bottom mirror)
			)
		)
		(property "Value" "TP_0.75mm_SMD"
			(at 0 -1.2 0)
			(layer "B.Fab")
			(hide yes)
			(effects
				(font
					(size 0.7 0.7)
					(thickness 0.15)
				)
				(justify left bottom mirror)
			)
		)
		(property "Description" "SMT test point"
			(at 0 0 0)
			(layer "B.Fab")
			(hide yes)
			(effects
				(font
					(size 1.27 1.27)
					(thickness 0.15)
				)
				(justify mirror)
			)
		)
		(property "MPN" ""
			(at 0 0 0)
			(unlocked yes)
			(layer "B.Fab")
			(hide yes)
			(effects
				(font
					(size 1 1)
					(thickness 0.15)
				)
				(justify mirror)
			)
		)
		(property "Manufacturer" ""
			(at 0 0 0)
			(unlocked yes)
			(layer "B.Fab")
			(hide yes)
			(effects
				(font
					(size 1 1)
					(thickness 0.15)
				)
				(justify mirror)
			)
		)
		(property "Author" "Antmicro"
			(at 0 0 0)
			(unlocked yes)
			(layer "B.Fab")
			(hide yes)
			(effects
				(font
					(size 1 1)
					(thickness 0.15)
				)
				(justify mirror)
			)
		)
		(property "License" "Apache-2.0"
			(at 0 0 0)
			(unlocked yes)
			(layer "B.Fab")
			(hide yes)
			(effects
				(font
					(size 1 1)
					(thickness 0.15)
				)
				(justify mirror)
			)
		)
		(property "Public" "False"
			(at 0 0 0)
			(unlocked yes)
			(layer "B.Fab")
			(hide yes)
			(effects
				(font
					(size 1 1)
					(thickness 0.15)
				)
				(justify mirror)
			)
		)
		(sheetname "/Supply/")
		(sheetfile "supply.kicad_sch")
		(attr exclude_from_pos_files exclude_from_bom)
		(fp_circle
			(center 0 0)
			(end 0.475 0)
			(stroke
				(width 0.05)
				(type default)
			)
			(fill no)
			(layer "B.CrtYd")
		)
		(fp_text user "License: Apache-2.0"
			(at -0.4 -5.101 0)
			(layer "B.Fab")
			(effects
				(font
					(size 0.7 0.7)
					(thickness 0.15)
				)
				(justify left bottom mirror)
			)
		)
		(fp_text user "${REFERENCE}"
			(at -0.4 -2.7 0)
			(layer "B.Fab")
			(effects
				(font
					(size 0.7 0.7)
					(thickness 0.15)
				)
				(justify left bottom mirror)
			)
		)
		(fp_text user "Author: Antmicro"
			(at -0.4 -3.901 0)
			(layer "B.Fab")
			(effects
				(font
					(size 0.7 0.7)
					(thickness 0.15)
				)
				(justify left bottom mirror)
			)
		)
		(pad "1" smd circle
			(at 0 0 180)
			(size 0.75 0.75)
			(layers "B.Cu" "B.Mask")
			(net 417 "GND")
			(pinfunction "1")
			(pintype "passive")
		)
	)
	(footprint "antmicro-footprints:SOT-523"
		(layer "B.Cu")
		(at 226.68 129.9 180)
		(property "Reference" "Q8"
			(at 2.505 0.325 180)
			(layer "B.SilkS")
			(effects
				(font
					(size 0.7 0.7)
					(thickness 0.15)
				)
				(justify left bottom mirror)
			)
		)
		(property "Value" "DMG1012T-7"
			(at 0.1 -1.824 0)
			(layer "B.Fab")
			(hide yes)
			(effects
				(font
					(size 0.7 0.7)
					(thickness 0.15)
				)
				(justify left bottom mirror)
			)
		)
		(property "Datasheet" "https://www.diodes.com/assets/Datasheets/ds31783.pdf"
			(at 0 0 180)
			(layer "F.Fab")
			(hide yes)
			(effects
				(font
					(size 1.27 1.27)
					(thickness 0.15)
				)
			)
		)
		(property "Description" "Power MOSFET, N Channel, 20 V, 630 mA, 0.3 ohm, SOT-523, Surface Mount"
			(at 0 0 180)
			(layer "F.Fab")
			(hide yes)
			(effects
				(font
					(size 1.27 1.27)
					(thickness 0.15)
				)
			)
		)
		(property "Author" "Antmicro"
			(at 453.36 259.8 0)
			(layer "B.Fab")
			(hide yes)
			(effects
				(font
					(size 1 1)
					(thickness 0.15)
				)
				(justify mirror)
			)
		)
		(property "License" "Apache-2.0"
			(at 453.36 259.8 0)
			(layer "B.Fab")
			(hide yes)
			(effects
				(font
					(size 1 1)
					(thickness 0.15)
				)
				(justify mirror)
			)
		)
		(property "MPN" "DMG1012T-7"
			(at 453.36 259.8 0)
			(layer "B.Fab")
			(hide yes)
			(effects
				(font
					(size 1 1)
					(thickness 0.15)
				)
				(justify mirror)
			)
		)
		(property "Manufacturer" "Diodes Incorporated"
			(at 453.36 259.8 0)
			(layer "B.Fab")
			(hide yes)
			(effects
				(font
					(size 1 1)
					(thickness 0.15)
				)
				(justify mirror)
			)
		)
		(property "Public" ""
			(at 453.36 259.8 0)
			(layer "B.Fab")
			(hide yes)
			(effects
				(font
					(size 1 1)
					(thickness 0.15)
				)
				(justify mirror)
			)
		)
		(sheetname "/FPGA GPIO/")
		(sheetfile "fpga-gpio.kicad_sch")
		(attr smd)
		(fp_line
			(start -0.277 0.551)
			(end -0.277 0.75)
			(stroke
				(width 0.15)
				(type solid)
			)
			(layer "B.SilkS")
		)
		(fp_line
			(start -0.725 0.551)
			(end -0.277 0.551)
			(stroke
				(width 0.15)
				(type solid)
			)
			(layer "B.SilkS")
		)
		(fp_line
			(start -0.927 0.351)
			(end -0.725 0.551)
			(stroke
				(width 0.15)
				(type solid)
			)
			(layer "B.SilkS")
		)
		(fp_line
			(start -0.927 0.051)
			(end -0.927 0.351)
			(stroke
				(width 0.15)
				(type solid)
			)
			(layer "B.SilkS")
		)
		(fp_circle
			(center -0.9652 -0.9652)
			(end -0.9152 -0.9652)
			(stroke
				(width 0.15)
				(type solid)
			)
			(fill yes)
			(layer "B.SilkS")
		)
		(fp_line
			(start 1.1 1.16)
			(end 1.1 -1.15)
			(stroke
				(width 0.05)
				(type solid)
			)
			(layer "B.CrtYd")
		)
		(fp_line
			(start -1.12 1.16)
			(end 1.1 1.16)
			(stroke
				(width 0.05)
				(type solid)
			)
			(layer "B.CrtYd")
		)
		(fp_line
			(start -1.12 1.16)
			(end -1.12 -1.15)
			(stroke
				(width 0.05)
				(type solid)
			)
			(layer "B.CrtYd")
		)
		(fp_line
			(start -1.12 -1.15)
			(end 1.1 -1.15)
			(stroke
				(width 0.05)
				(type solid)
			)
			(layer "B.CrtYd")
		)
		(fp_line
			(start 0.8 0.425)
			(end 0.8 -0.424)
			(stroke
				(width 0.15)
				(type solid)
			)
			(layer "B.Fab")
		)
		(fp_line
			(start 0.8 0.425)
			(end -0.652 0.425)
			(stroke
				(width 0.15)
				(type solid)
			)
			(layer "B.Fab")
		)
		(fp_line
			(start 0.8 -0.424)
			(end -0.802 -0.424)
			(stroke
				(width 0.15)
				(type solid)
			)
			(layer "B.Fab")
		)
		(fp_line
			(start -0.652 0.425)
			(end -0.802 0.276)
			(stroke
				(width 0.15)
				(type solid)
			)
			(layer "B.Fab")
		)
		(fp_line
			(start -0.802 0.276)
			(end -0.802 -0.424)
			(stroke
				(width 0.15)
				(type solid)
			)
			(layer "B.Fab")
		)
		(fp_circle
			(center -0.9652 -0.9652)
			(end -0.9144 -0.9652)
			(stroke
				(width 0.15)
				(type solid)
			)
			(fill no)
			(layer "B.Fab")
		)
		(fp_text user "License: Apache-2.0"
			(at -1.12 -5.024 0)
			(layer "B.Fab")
			(effects
				(font
					(size 0.7 0.7)
					(thickness 0.15)
				)
				(justify left bottom mirror)
			)
		)
		(fp_text user "Author: Antmicro"
			(at -1.12 -6.224 0)
			(layer "B.Fab")
			(effects
				(font
					(size 0.7 0.7)
					(thickness 0.15)
				)
				(justify left bottom mirror)
			)
		)
		(fp_text user "${REFERENCE}"
			(at -1.12 -3.824 0)
			(layer "B.Fab")
			(effects
				(font
					(size 0.7 0.7)
					(thickness 0.15)
				)
				(justify left bottom mirror)
			)
		)
		(pad "1" smd rect
			(at -0.5 -0.65 180)
			(size 0.4 0.51)
			(layers "B.Cu" "B.Mask" "B.Paste")
			(net 342 "/FPGA GPIO/USER_LED_R")
			(pinfunction "G")
			(pintype "input")
		)
		(pad "2" smd rect
			(at 0.498 -0.65 180)
			(size 0.4 0.51)
			(layers "B.Cu" "B.Mask" "B.Paste")
			(net 417 "GND")
			(pinfunction "S")
			(pintype "passive")
		)
		(pad "3" smd rect
			(at 0 0.652 180)
			(size 0.4 0.51)
			(layers "B.Cu" "B.Mask" "B.Paste")
			(net 542 "Net-(Q8-D)")
			(pinfunction "D")
			(pintype "passive")
		)
	)
)
